(kicad_pcb
	(version 20260206)
	(generator "pcbnew")
	(generator_version "10.0")
	(general
		(thickness 1.6)
		(legacy_teardrops no)
	)
	(paper "A4")
	(title_block
		(title "Bryce Canyon_Front Panel_16369-1_OCP.brd")
		(comment 1 "Bryce Canyon / footprints 95-98 of 154")
	)
	(layers
		(0 "F.Cu" signal "TOP")
		(4 "In1.Cu" signal "L2GND")
		(6 "In2.Cu" signal "L3VCC")
		(2 "B.Cu" signal "BOTTOM")
		(9 "F.Adhes" user "F.Adhesive")
		(11 "B.Adhes" user "B.Adhesive")
		(13 "F.Paste" user "Package Geometry/Pastemask Top")
		(15 "B.Paste" user "Package Geometry/Pastemask Bottom")
		(5 "F.SilkS" user "Ref Des/Silkscreen Top")
		(7 "B.SilkS" user "Ref Des/Silkscreen Bottom")
		(1 "F.Mask" user "Board Geometry/Soldermask Top")
		(3 "B.Mask" user "Board Geometry/Soldermask Bottom")
		(17 "Dwgs.User" user "User.Drawings")
		(19 "Cmts.User" user "User.Comments")
		(21 "Eco1.User" user "User.Eco1")
		(23 "Eco2.User" user "User.Eco2")
		(25 "Edge.Cuts" user "Board Geometry/Outline")
		(27 "Margin" user)
		(31 "F.CrtYd" user "Package Geometry/Place Bound Top")
		(29 "B.CrtYd" user "Package Geometry/Place Bound Bottom")
		(35 "F.Fab" user "Ref Des/Assembly Top")
		(33 "B.Fab" user "Ref Des/Assembly Bottom")
	)
	(footprint ""
		(layer "F.Cu")
		(at 47.900082 -43.999912 90)
		(property "Reference" "LED2"
			(at 0 0 90)
			(layer "F.SilkS")
			(hide yes)
			(effects
				(font
					(size 1.27 1.27)
				)
			)
		)
		(property "Value" "LED-Y-167-GP"
			(at 3.3274 -0.4572 90)
			(unlocked yes)
			(layer "F.Fab")
			(hide yes)
			(effects
				(font
					(size 1.016 1.016)
					(thickness 0.1524)
				)
			)
		)
		(property "Device Type" "LED-100-4035-1A2KH274"
			(at 3.3274 -1.9812 90)
			(unlocked yes)
			(layer "F.Fab")
			(hide yes)
			(effects
				(font
					(size 1.016 1.016)
					(thickness 0.1524)
				)
			)
		)
		(duplicate_pad_numbers_are_jumpers no)
		(fp_line
			(start 1.905 -0.254)
			(end 1.397 0.254)
			(stroke
				(width 0.1524)
				(type default)
			)
			(layer "F.SilkS")
		)
		(fp_line
			(start 1.397 -0.254)
			(end 1.397 -0.762)
			(stroke
				(width 0.1524)
				(type default)
			)
			(layer "F.SilkS")
		)
		(fp_line
			(start 0.889 -0.254)
			(end 1.905 -0.254)
			(stroke
				(width 0.1524)
				(type default)
			)
			(layer "F.SilkS")
		)
		(fp_line
			(start 1.397 0.254)
			(end 0.889 -0.254)
			(stroke
				(width 0.1524)
				(type default)
			)
			(layer "F.SilkS")
		)
		(fp_line
			(start 1.397 0.254)
			(end 1.397 0.762)
			(stroke
				(width 0.1524)
				(type default)
			)
			(layer "F.SilkS")
		)
		(fp_line
			(start 0.889 0.254)
			(end 1.905 0.254)
			(stroke
				(width 0.1524)
				(type default)
			)
			(layer "F.SilkS")
		)
		(fp_line
			(start 1.427988 1.7526)
			(end 0.685546 1.7526)
			(stroke
				(width 0.1524)
				(type default)
			)
			(layer "F.SilkS")
		)
		(fp_line
			(start -0.685546 1.7526)
			(end -1.427988 1.7526)
			(stroke
				(width 0.1524)
				(type default)
			)
			(layer "F.SilkS")
		)
		(fp_arc
			(start 0.685546 1.7526)
			(mid 0 2.108377)
			(end -0.685546 1.7526)
			(stroke
				(width 0.1524)
				(type default)
			)
			(layer "F.SilkS")
		)
		(fp_arc
			(start -1.427988 1.7526)
			(mid 0 -2.260698)
			(end 1.427988 1.7526)
			(stroke
				(width 0.1524)
				(type default)
			)
			(layer "F.SilkS")
		)
		(fp_circle
			(center 0 -1.27)
			(end 0 -0.3302)
			(stroke
				(width 0.3048)
				(type default)
			)
			(fill no)
			(layer "F.SilkS")
		)
		(fp_circle
			(center 0 1.27)
			(end 0 2.2098)
			(stroke
				(width 0.3048)
				(type default)
			)
			(fill no)
			(layer "F.SilkS")
		)
		(fp_poly
			(pts
				(arc
					(start -1.334516 1.4986)
					(mid 0 -2.006673)
					(end 1.334516 1.4986)
				)
			)
			(stroke
				(width 0)
				(type default)
			)
			(fill no)
			(layer "F.CrtYd")
		)
		(fp_poly
			(pts
				(arc
					(start 0.806704 2.0066)
					(mid 0 2.362406)
					(end -0.806704 2.0066)
				)
				(arc
					(start -1.515618 2.0066)
					(mid -1.123616 -2.249673)
					(end 2.5146 -0.00635)
				)
				(arc
					(start 2.006854 -0.00635)
					(mid -0.824269 -1.829777)
					(end -1.334516 1.498854)
				)
				(arc
					(start 1.334516 1.498854)
					(mid 1.829775 0.824269)
					(end 2.006854 0.00635)
				)
				(arc
					(start 2.5146 0.00635)
					(mid 2.249622 1.12359)
					(end 1.515618 2.0066)
				)
			)
			(stroke
				(width 0)
				(type default)
			)
			(fill no)
			(layer "F.CrtYd")
		)
		(fp_poly
			(pts
				(arc
					(start 0.806704 2.0066)
					(mid 0 2.362406)
					(end -0.806704 2.0066)
				)
				(arc
					(start -1.515618 2.0066)
					(mid 0 -2.514665)
					(end 1.515618 2.0066)
				)
			)
			(stroke
				(width 0)
				(type default)
			)
			(fill no)
			(layer "F.Fab")
		)
		(pad "1A" thru_hole circle
			(at 0 -1.27 90)
			(size 1.1684 1.1684)
			(drill 0.8128)
			(layers "*.Cu" "*.Mask")
			(remove_unused_layers no)
			(net "SYS_FAULT_B_R")
			(clearance 0.1778)
			(thermal_gap 0.1778)
		)
		(pad "2K" thru_hole circle
			(at 0 1.27 90)
			(size 1.1684 1.1684)
			(drill 0.8128)
			(layers "*.Cu" "*.Mask")
			(remove_unused_layers no)
			(net "FAULT_LED_B")
			(clearance 0.1778)
			(thermal_gap 0.1778)
		)
	)
	(footprint ""
		(layer "F.Cu")
		(at 14.8336 -20.193 90)
		(property "Reference" "U2"
			(at 0 0 90)
			(layer "F.SilkS")
			(hide yes)
			(effects
				(font
					(size 1.27 1.27)
				)
			)
		)
		(property "Value" "TCA9555PWR-GP"
			(at 0 -6.9342 90)
			(unlocked yes)
			(layer "F.Fab")
			(hide yes)
			(effects
				(font
					(size 1.016 1.016)
					(thickness 0.1524)
				)
			)
		)
		(property "Device Type" "TSOIC24H48"
			(at 0 -8.5852 90)
			(unlocked yes)
			(layer "F.Fab")
			(hide yes)
			(effects
				(font
					(size 1.016 1.016)
					(thickness 0.1524)
				)
			)
		)
		(duplicate_pad_numbers_are_jumpers no)
		(fp_line
			(start 3.81 -1.397)
			(end 3.81 1.397)
			(stroke
				(width 0.1524)
				(type default)
			)
			(layer "F.SilkS")
		)
		(fp_line
			(start -4.2291 -1.397)
			(end 3.81 -1.397)
			(stroke
				(width 0.1524)
				(type default)
			)
			(layer "F.SilkS")
		)
		(fp_line
			(start -4.2291 -0.8001)
			(end -3.429 0)
			(stroke
				(width 0.1524)
				(type default)
			)
			(layer "F.SilkS")
		)
		(fp_line
			(start -3.429 0)
			(end -4.2291 0.8001)
			(stroke
				(width 0.1524)
				(type default)
			)
			(layer "F.SilkS")
		)
		(fp_line
			(start 3.81 1.397)
			(end -4.2291 1.397)
			(stroke
				(width 0.1524)
				(type default)
			)
			(layer "F.SilkS")
		)
		(fp_line
			(start -4.22656 3.81)
			(end -4.2291 1.397)
			(stroke
				(width 0.508)
				(type default)
			)
			(layer "F.SilkS")
		)
		(fp_line
			(start -4.2291 3.937)
			(end -4.2291 -1.397)
			(stroke
				(width 0.1524)
				(type default)
			)
			(layer "F.SilkS")
		)
		(fp_poly
			(pts
				(xy -3.90652 -1.8542) (xy 3.90652 -1.8542) (xy 3.90652 1.8542) (xy -3.90652 1.8542)
			)
			(stroke
				(width 0)
				(type default)
			)
			(fill yes)
			(layer "F.SilkS")
		)
		(fp_poly
			(pts
				(xy -4.2164 3.81) (xy 4.2164 3.81) (xy 4.22656 -3.81) (xy -4.2164 -3.81)
			)
			(stroke
				(width 0)
				(type default)
			)
			(fill no)
			(layer "F.CrtYd")
		)
		(fp_poly
			(pts
				(xy -4.22656 -3.81) (xy 4.22656 -3.81) (xy 4.22656 3.81) (xy -4.22656 3.81)
			)
			(stroke
				(width 0)
				(type default)
			)
			(fill no)
			(layer "F.Fab")
		)
		(pad "1" smd rect
			(at -3.57632 2.8194 90)
			(size 0.3556 1.524)
			(layers "F.Cu" "F.Mask" "F.Paste")
			(net "IO_EXP_A_RESET#_FLT")
		)
		(pad "2" smd rect
			(at -2.92608 2.8194 90)
			(size 0.3556 1.524)
			(layers "F.Cu" "F.Mask" "F.Paste")
			(net "TCA9555_A_A1")
		)
		(pad "3" smd rect
			(at -2.27584 2.8194 90)
			(size 0.3556 1.524)
			(layers "F.Cu" "F.Mask" "F.Paste")
			(net "TCA9555_A_A2")
		)
		(pad "4" smd rect
			(at -1.6256 2.8194 90)
			(size 0.3556 1.524)
			(layers "F.Cu" "F.Mask" "F.Paste")
			(net "Net_67")
		)
		(pad "5" smd rect
			(at -0.97536 2.8194 90)
			(size 0.3556 1.524)
			(layers "F.Cu" "F.Mask" "F.Paste")
			(net "Net_66")
		)
		(pad "6" smd rect
			(at -0.32512 2.8194 90)
			(size 0.3556 1.524)
			(layers "F.Cu" "F.Mask" "F.Paste")
			(net "Net_65")
		)
		(pad "7" smd rect
			(at 0.32512 2.8194 90)
			(size 0.3556 1.524)
			(layers "F.Cu" "F.Mask" "F.Paste")
			(net "Net_64")
		)
		(pad "8" smd rect
			(at 0.97536 2.8194 90)
			(size 0.3556 1.524)
			(layers "F.Cu" "F.Mask" "F.Paste")
			(net "Net_63")
		)
		(pad "9" smd rect
			(at 1.6256 2.8194 90)
			(size 0.3556 1.524)
			(layers "F.Cu" "F.Mask" "F.Paste")
			(net "Net_62")
		)
		(pad "10" smd rect
			(at 2.27584 2.8194 90)
			(size 0.3556 1.524)
			(layers "F.Cu" "F.Mask" "F.Paste")
			(net "Net_61")
		)
		(pad "11" smd rect
			(at 2.92608 2.8194 90)
			(size 0.3556 1.524)
			(layers "F.Cu" "F.Mask" "F.Paste")
			(net "Net_60")
		)
		(pad "12" smd rect
			(at 3.57632 2.8194 90)
			(size 0.3556 1.524)
			(layers "F.Cu" "F.Mask" "F.Paste")
			(net "GND")
		)
		(pad "13" smd rect
			(at 3.57632 -2.8194 90)
			(size 0.3556 1.524)
			(layers "F.Cu" "F.Mask" "F.Paste")
			(net "DEBUG_RST_A_BTN_N")
		)
		(pad "14" smd rect
			(at 2.92608 -2.8194 90)
			(size 0.3556 1.524)
			(layers "F.Cu" "F.Mask" "F.Paste")
			(net "Net_59")
		)
		(pad "15" smd rect
			(at 2.27584 -2.8194 90)
			(size 0.3556 1.524)
			(layers "F.Cu" "F.Mask" "F.Paste")
			(net "Net_58")
		)
		(pad "16" smd rect
			(at 1.6256 -2.8194 90)
			(size 0.3556 1.524)
			(layers "F.Cu" "F.Mask" "F.Paste")
			(net "Net_57")
		)
		(pad "17" smd rect
			(at 0.97536 -2.8194 90)
			(size 0.3556 1.524)
			(layers "F.Cu" "F.Mask" "F.Paste")
			(net "Net_56")
		)
		(pad "18" smd rect
			(at 0.32512 -2.8194 90)
			(size 0.3556 1.524)
			(layers "F.Cu" "F.Mask" "F.Paste")
			(net "Net_55")
		)
		(pad "19" smd rect
			(at -0.32512 -2.8194 90)
			(size 0.3556 1.524)
			(layers "F.Cu" "F.Mask" "F.Paste")
			(net "Net_54")
		)
		(pad "20" smd rect
			(at -0.97536 -2.8194 90)
			(size 0.3556 1.524)
			(layers "F.Cu" "F.Mask" "F.Paste")
			(net "DEBUG_HDR_A_UART_SEL")
		)
		(pad "21" smd rect
			(at -1.6256 -2.8194 90)
			(size 0.3556 1.524)
			(layers "F.Cu" "F.Mask" "F.Paste")
			(net "TCA9555_A_A0")
		)
		(pad "22" smd rect
			(at -2.27584 -2.8194 90)
			(size 0.3556 1.524)
			(layers "F.Cu" "F.Mask" "F.Paste")
			(net "I2C_DEBUG_A_SCL_R")
		)
		(pad "23" smd rect
			(at -2.92608 -2.8194 90)
			(size 0.3556 1.524)
			(layers "F.Cu" "F.Mask" "F.Paste")
			(net "I2C_DEBUG_A_SDA_R")
		)
		(pad "24" smd rect
			(at -3.57632 -2.8194 90)
			(size 0.3556 1.524)
			(layers "F.Cu" "F.Mask" "F.Paste")
			(net "P3V3_STBY_A")
		)
	)
	(footprint ""
		(layer "F.Cu")
		(at 6.0706 -17.9832 90)
		(property "Reference" "R56"
			(at 0 0 90)
			(layer "F.SilkS")
			(hide yes)
			(effects
				(font
					(size 1.27 1.27)
				)
			)
		)
		(property "Value" "20KR2F-L-GP"
			(at 0.064008 -3.993896 90)
			(unlocked yes)
			(layer "F.Fab")
			(hide yes)
			(effects
				(font
					(size 1.016 1.016)
					(thickness 0.1524)
				)
			)
		)
		(property "Device Type" "R402H16"
			(at 0.064008 -5.517896 90)
			(unlocked yes)
			(layer "F.Fab")
			(hide yes)
			(effects
				(font
					(size 1.016 1.016)
					(thickness 0.1524)
				)
			)
		)
		(duplicate_pad_numbers_are_jumpers no)
		(fp_line
			(start 0.508 -0.9398)
			(end -0.508 -0.9398)
			(stroke
				(width 0.1524)
				(type default)
			)
			(layer "F.SilkS")
		)
		(fp_line
			(start -0.508 -0.9398)
			(end -0.508 0.9398)
			(stroke
				(width 0.1524)
				(type default)
			)
			(layer "F.SilkS")
		)
		(fp_rect
			(start -0.508 0.9398)
			(end 0.508 -0.9398)
			(stroke
				(width 0)
				(type default)
			)
			(fill no)
			(layer "F.CrtYd")
		)
		(fp_rect
			(start -0.508 0.9398)
			(end 0.508 -0.9398)
			(stroke
				(width 0)
				(type default)
			)
			(fill no)
			(layer "F.Fab")
		)
		(pad "1" smd custom
			(at 0 -0.4445 90)
			(size 0.1397 0.1397)
			(layers "F.Cu" "F.Mask" "F.Paste")
			(net "P3V3_STBY_A")
			(options
				(clearance outline)
				(anchor circle)
			)
			(primitives
				(gr_poly
					(pts
						(arc
							(start -0.1778 -0.2794)
							(mid -0.249642 -0.249642)
							(end -0.2794 -0.1778)
						)
						(arc
							(start -0.2794 0.1778)
							(mid -0.249642 0.249642)
							(end -0.1778 0.2794)
						)
						(arc
							(start 0.1778 0.2794)
							(mid 0.249642 0.249642)
							(end 0.2794 0.1778)
						)
						(arc
							(start 0.2794 -0.1778)
							(mid 0.249642 -0.249642)
							(end 0.1778 -0.2794)
						)
					)
					(width 0)
					(fill yes)
				)
			)
		)
		(pad "2" smd custom
			(at 0 0.4445 90)
			(size 0.1397 0.1397)
			(layers "F.Cu" "F.Mask" "F.Paste")
			(net "I2C_DEBUG_A_SCL_L")
			(options
				(clearance outline)
				(anchor circle)
			)
			(primitives
				(gr_poly
					(pts
						(arc
							(start -0.1778 -0.2794)
							(mid -0.249642 -0.249642)
							(end -0.2794 -0.1778)
						)
						(arc
							(start -0.2794 0.1778)
							(mid -0.249642 0.249642)
							(end -0.1778 0.2794)
						)
						(arc
							(start 0.1778 0.2794)
							(mid 0.249642 0.249642)
							(end 0.2794 0.1778)
						)
						(arc
							(start 0.2794 -0.1778)
							(mid 0.249642 -0.249642)
							(end 0.1778 -0.2794)
						)
					)
					(width 0)
					(fill yes)
				)
			)
		)
	)
	(footprint ""
		(layer "F.Cu")
		(at 53.052218 -71.995792 90)
		(property "Reference" "R46"
			(at 0 0 90)
			(layer "F.SilkS")
			(hide yes)
			(effects
				(font
					(size 1.27 1.27)
				)
			)
		)
		(property "Value" "1MR2F-GP"
			(at 0.064008 -4.679696 90)
			(unlocked yes)
			(layer "F.Fab")
			(hide yes)
			(effects
				(font
					(size 2.54 2.54)
					(thickness 0.381)
				)
			)
		)
		(property "Device Type" "R402H16"
			(at 0.064008 -6.203696 90)
			(unlocked yes)
			(layer "F.Fab")
			(hide yes)
			(effects
				(font
					(size 2.54 2.54)
					(thickness 0.381)
				)
			)
		)
		(duplicate_pad_numbers_are_jumpers no)
		(fp_line
			(start 0.508 -0.9398)
			(end -0.508 -0.9398)
			(stroke
				(width 0.1524)
				(type default)
			)
			(layer "F.SilkS")
		)
		(fp_line
			(start -0.508 -0.9398)
			(end -0.508 0.9398)
			(stroke
				(width 0.1524)
				(type default)
			)
			(layer "F.SilkS")
		)
		(fp_rect
			(start -0.508 0.9398)
			(end 0.508 -0.9398)
			(stroke
				(width 0)
				(type default)
			)
			(fill no)
			(layer "F.CrtYd")
		)
		(fp_rect
			(start -0.508 0.9398)
			(end 0.508 -0.9398)
			(stroke
				(width 0)
				(type default)
			)
			(fill no)
			(layer "F.Fab")
		)
		(pad "1" smd custom
			(at 0 -0.4445 90)
			(size 0.1397 0.1397)
			(layers "F.Cu" "F.Mask" "F.Paste")
			(net "USB_CONN_B_GND")
			(options
				(clearance outline)
				(anchor circle)
			)
			(primitives
				(gr_poly
					(pts
						(arc
							(start -0.1778 -0.2794)
							(mid -0.249642 -0.249642)
							(end -0.2794 -0.1778)
						)
						(arc
							(start -0.2794 0.1778)
							(mid -0.249642 0.249642)
							(end -0.1778 0.2794)
						)
						(arc
							(start 0.1778 0.2794)
							(mid 0.249642 0.249642)
							(end 0.2794 0.1778)
						)
						(arc
							(start 0.2794 -0.1778)
							(mid 0.249642 -0.249642)
							(end 0.1778 -0.2794)
						)
					)
					(width 0)
					(fill yes)
				)
			)
		)
		(pad "2" smd custom
			(at 0 0.4445 90)
			(size 0.1397 0.1397)
			(layers "F.Cu" "F.Mask" "F.Paste")
			(net "GND")
			(options
				(clearance outline)
				(anchor circle)
			)
			(primitives
				(gr_poly
					(pts
						(arc
							(start -0.1778 -0.2794)
							(mid -0.249642 -0.249642)
							(end -0.2794 -0.1778)
						)
						(arc
							(start -0.2794 0.1778)
							(mid -0.249642 0.249642)
							(end -0.1778 0.2794)
						)
						(arc
							(start 0.1778 0.2794)
							(mid 0.249642 0.249642)
							(end 0.2794 0.1778)
						)
						(arc
							(start 0.2794 -0.1778)
							(mid 0.249642 -0.249642)
							(end 0.1778 -0.2794)
						)
					)
					(width 0)
					(fill yes)
				)
			)
		)
	)
)
